# T6G (Grand Teton) — schematic netlist excerpt (pin names and nets, part order shuffled) for the footprints in the layout excerpt that follows; sources: Cadence DE-HDL packaged netlist, KiCad conversion of 04192023_DAF0TMB3IC0_F0TG_MB_C_brd_V02_OCP.brd

C652  Q_CAP  4.7UF 6.3V 20% X6S  pkg 0402  page 290 : A = P0V9_CPU0_RT1_2A ; B = GND
C2333  Q_CAP  22UF 4V 20% X6S  pkg C0402  page 73 : A = PVDDCR_CPU0_P1 ; B = GND

(kicad_pcb
	(version 20260206)
	(generator "pcbnew")
	(generator_version "10.0")
	(general
		(thickness 1.6)
		(legacy_teardrops no)
	)
	(paper "A4")
	(title_block
		(title "04192023_DAF0TMB3IC0_F0TG_MB_C_brd_V02_OCP.brd")
		(comment 1 "Grand Teton / footprints 8017-8018 of 8354")
	)
	(layers
		(0 "F.Cu" signal "TOP")
		(4 "In1.Cu" signal "GND")
		(6 "In2.Cu" signal "IN1")
		(8 "In3.Cu" signal "GND1")
		(10 "In4.Cu" signal "IN2")
		(12 "In5.Cu" signal "GND2")
		(14 "In6.Cu" signal "IN3")
		(16 "In7.Cu" signal "GND3")
		(18 "In8.Cu" signal "VCC")
		(20 "In9.Cu" signal "VCC1")
		(22 "In10.Cu" signal "GND4")
		(24 "In11.Cu" signal "IN4")
		(26 "In12.Cu" signal "GND5")
		(28 "In13.Cu" signal "IN5")
		(30 "In14.Cu" signal "GND6")
		(32 "In15.Cu" signal "IN6")
		(34 "In16.Cu" signal "GND7")
		(2 "B.Cu" signal "BOTTOM")
		(9 "F.Adhes" user "F.Adhesive")
		(11 "B.Adhes" user "B.Adhesive")
		(13 "F.Paste" user "Package Geometry/Pastemask Top")
		(15 "B.Paste" user "Package Geometry/Pastemask Bottom")
		(5 "F.SilkS" user "Ref Des/Silkscreen Top")
		(7 "B.SilkS" user "Ref Des/Silkscreen Bottom")
		(1 "F.Mask" user "Board Geometry/Soldermask Top")
		(3 "B.Mask" user "Board Geometry/Soldermask Bottom")
		(17 "Dwgs.User" user "User.Drawings")
		(19 "Cmts.User" user "User.Comments")
		(21 "Eco1.User" user "User.Eco1")
		(23 "Eco2.User" user "User.Eco2")
		(25 "Edge.Cuts" user "Board Geometry/Outline")
		(27 "Margin" user)
		(31 "F.CrtYd" user "Package Geometry/Place Bound Top")
		(29 "B.CrtYd" user "Package Geometry/Place Bound Bottom")
		(35 "F.Fab" user "Ref Des/Assembly Top")
		(33 "B.Fab" user "Ref Des/Assembly Bottom")
	)
	(footprint ""
		(layer "B.Cu")
		(at 124.97689 -248.479564)
		(property "Reference" "C2333"
			(at 0 0 0)
			(layer "B.SilkS")
			(hide yes)
			(effects
				(font
					(size 1.27 1.27)
				)
				(justify mirror)
			)
		)
		(property "Value" ""
			(at 0 0 0)
			(layer "B.Fab")
			(effects
				(font
					(size 1.27 1.27)
				)
				(justify mirror)
			)
		)
		(duplicate_pad_numbers_are_jumpers no)
		(fp_line
			(start -0.7874 -0.4064)
			(end -0.7874 0.4064)
			(stroke
				(width 0.1524)
				(type default)
			)
			(layer "B.SilkS")
		)
		(fp_line
			(start -0.7874 0.4064)
			(end 0.7874 0.4064)
			(stroke
				(width 0.1524)
				(type default)
			)
			(layer "B.SilkS")
		)
		(fp_line
			(start 0.7874 -0.4064)
			(end -0.7874 -0.4064)
			(stroke
				(width 0.1524)
				(type default)
			)
			(layer "B.SilkS")
		)
		(fp_line
			(start 0.7874 0.4064)
			(end 0.7874 -0.4064)
			(stroke
				(width 0.1524)
				(type default)
			)
			(layer "B.SilkS")
		)
		(fp_line
			(start -0.67945 -0.3048)
			(end -0.67945 0.3048)
			(stroke
				(width 0.1)
				(type default)
			)
			(layer "B.Fab")
		)
		(fp_line
			(start -0.67945 0.3048)
			(end -0.120396 0.3048)
			(stroke
				(width 0.1)
				(type default)
			)
			(layer "B.Fab")
		)
		(fp_line
			(start -0.12065 -0.3048)
			(end -0.67945 -0.3048)
			(stroke
				(width 0.1)
				(type default)
			)
			(layer "B.Fab")
		)
		(fp_line
			(start -0.12065 -0.2794)
			(end -0.12065 -0.3048)
			(stroke
				(width 0.1)
				(type default)
			)
			(layer "B.Fab")
		)
		(fp_line
			(start -0.120396 0.2794)
			(end 0.12065 0.2794)
			(stroke
				(width 0.1)
				(type default)
			)
			(layer "B.Fab")
		)
		(fp_line
			(start -0.120396 0.3048)
			(end -0.120396 0.2794)
			(stroke
				(width 0.1)
				(type default)
			)
			(layer "B.Fab")
		)
		(fp_line
			(start 0.12065 -0.305054)
			(end 0.12065 -0.2794)
			(stroke
				(width 0.1)
				(type default)
			)
			(layer "B.Fab")
		)
		(fp_line
			(start 0.12065 -0.2794)
			(end -0.12065 -0.2794)
			(stroke
				(width 0.1)
				(type default)
			)
			(layer "B.Fab")
		)
		(fp_line
			(start 0.12065 0.2794)
			(end 0.12065 0.3048)
			(stroke
				(width 0.1)
				(type default)
			)
			(layer "B.Fab")
		)
		(fp_line
			(start 0.12065 0.3048)
			(end 0.67945 0.3048)
			(stroke
				(width 0.1)
				(type default)
			)
			(layer "B.Fab")
		)
		(fp_line
			(start 0.67945 -0.305054)
			(end 0.12065 -0.305054)
			(stroke
				(width 0.1)
				(type default)
			)
			(layer "B.Fab")
		)
		(fp_line
			(start 0.67945 0.3048)
			(end 0.67945 -0.305054)
			(stroke
				(width 0.1)
				(type default)
			)
			(layer "B.Fab")
		)
		(pad "1" smd circle
			(at 0.40005 0 180)
			(size 0 0)
			(layers "B.Cu" "B.Mask" "B.Paste")
			(net "PVDDCR_CPU0_P1")
		)
		(pad "2" smd circle
			(at -0.40005 0 180)
			(size 0 0)
			(layers "B.Cu" "B.Mask" "B.Paste")
			(net "GND")
		)
	)
	(footprint ""
		(layer "B.Cu")
		(at 352.718878 -398.942052 90)
		(property "Reference" "C652"
			(at 0 0 90)
			(layer "B.SilkS")
			(hide yes)
			(effects
				(font
					(size 1.27 1.27)
				)
				(justify mirror)
			)
		)
		(property "Value" ""
			(at 0 0 90)
			(layer "B.Fab")
			(effects
				(font
					(size 1.27 1.27)
				)
				(justify mirror)
			)
		)
		(duplicate_pad_numbers_are_jumpers no)
		(fp_line
			(start 0.7874 -0.4064)
			(end -0.7874 -0.4064)
			(stroke
				(width 0.1524)
				(type default)
			)
			(layer "B.SilkS")
		)
		(fp_line
			(start -0.7874 -0.4064)
			(end -0.7874 0.4064)
			(stroke
				(width 0.1524)
				(type default)
			)
			(layer "B.SilkS")
		)
		(fp_line
			(start 0.7874 0.4064)
			(end 0.7874 -0.4064)
			(stroke
				(width 0.1524)
				(type default)
			)
			(layer "B.SilkS")
		)
		(fp_line
			(start -0.7874 0.4064)
			(end 0.7874 0.4064)
			(stroke
				(width 0.1524)
				(type default)
			)
			(layer "B.SilkS")
		)
		(fp_line
			(start 0.67945 -0.305054)
			(end 0.12065 -0.305054)
			(stroke
				(width 0.1)
				(type default)
			)
			(layer "B.Fab")
		)
		(fp_line
			(start 0.12065 -0.305054)
			(end 0.12065 -0.2794)
			(stroke
				(width 0.1)
				(type default)
			)
			(layer "B.Fab")
		)
		(fp_line
			(start -0.12065 -0.3048)
			(end -0.67945 -0.3048)
			(stroke
				(width 0.1)
				(type default)
			)
			(layer "B.Fab")
		)
		(fp_line
			(start -0.67945 -0.3048)
			(end -0.67945 0.3048)
			(stroke
				(width 0.1)
				(type default)
			)
			(layer "B.Fab")
		)
		(fp_line
			(start 0.12065 -0.2794)
			(end -0.12065 -0.2794)
			(stroke
				(width 0.1)
				(type default)
			)
			(layer "B.Fab")
		)
		(fp_line
			(start -0.12065 -0.2794)
			(end -0.12065 -0.3048)
			(stroke
				(width 0.1)
				(type default)
			)
			(layer "B.Fab")
		)
		(fp_line
			(start 0.12065 0.2794)
			(end 0.12065 0.3048)
			(stroke
				(width 0.1)
				(type default)
			)
			(layer "B.Fab")
		)
		(fp_line
			(start -0.120396 0.2794)
			(end 0.12065 0.2794)
			(stroke
				(width 0.1)
				(type default)
			)
			(layer "B.Fab")
		)
		(fp_line
			(start 0.67945 0.3048)
			(end 0.67945 -0.305054)
			(stroke
				(width 0.1)
				(type default)
			)
			(layer "B.Fab")
		)
		(fp_line
			(start 0.12065 0.3048)
			(end 0.67945 0.3048)
			(stroke
				(width 0.1)
				(type default)
			)
			(layer "B.Fab")
		)
		(fp_line
			(start -0.120396 0.3048)
			(end -0.120396 0.2794)
			(stroke
				(width 0.1)
				(type default)
			)
			(layer "B.Fab")
		)
		(fp_line
			(start -0.67945 0.3048)
			(end -0.120396 0.3048)
			(stroke
				(width 0.1)
				(type default)
			)
			(layer "B.Fab")
		)
		(pad "1" smd circle
			(at 0.40005 0 270)
			(size 0 0)
			(layers "B.Cu" "B.Mask" "B.Paste")
			(net "P0V9_CPU0_RT1_2A")
		)
		(pad "2" smd circle
			(at -0.40005 0 270)
			(size 0 0)
			(layers "B.Cu" "B.Mask" "B.Paste")
			(net "GND")
		)
	)
)
